(kicad_pcb
	(version 20260206)
	(generator "pcbnew")
	(generator_version "10.0")
	(general
		(thickness 1.6)
		(legacy_teardrops no)
	)
	(paper "A4")
	(title_block
		(title "netronome-mezz — pcbd0082-001_rev01_jul9_a.brd")
		(comment 1 "Open CloudServer (Microsoft) / footprints 271-279 of 714")
	)
	(layers
		(0 "F.Cu" signal "TOP")
		(4 "In1.Cu" signal "02_GND")
		(6 "In2.Cu" signal "03_SIG")
		(8 "In3.Cu" signal "04_SIG")
		(10 "In4.Cu" signal "05_GND")
		(12 "In5.Cu" signal "06_PWR1")
		(14 "In6.Cu" signal "07_SIG")
		(16 "In7.Cu" signal "08_SIG")
		(18 "In8.Cu" signal "09_GND")
		(2 "B.Cu" signal "BOTTOM")
		(9 "F.Adhes" user "F.Adhesive")
		(11 "B.Adhes" user "B.Adhesive")
		(13 "F.Paste" user "Package Geometry/Pastemask Top")
		(15 "B.Paste" user "Package Geometry/Pastemask Bottom")
		(5 "F.SilkS" user "Ref Des/Silkscreen Top")
		(7 "B.SilkS" user "Ref Des/Silkscreen Bottom")
		(1 "F.Mask" user "Board Geometry/Soldermask Top")
		(3 "B.Mask" user "Board Geometry/Soldermask Bottom")
		(17 "Dwgs.User" user "User.Drawings")
		(19 "Cmts.User" user "User.Comments")
		(21 "Eco1.User" user "User.Eco1")
		(23 "Eco2.User" user "User.Eco2")
		(25 "Edge.Cuts" user "Board Geometry/Outline")
		(27 "Margin" user)
		(31 "F.CrtYd" user "Package Geometry/Place Bound Top")
		(29 "B.CrtYd" user "Package Geometry/Place Bound Bottom")
		(35 "F.Fab" user "Ref Des/Assembly Top")
		(33 "B.Fab" user "Ref Des/Assembly Bottom")
		(45 "User.4" user "COMPVAL_TYPE_BOTTOM")
	)
	(footprint ""
		(layer "F.Cu")
		(at 45.466 53.1368 -90)
		(property "Reference" "R278"
			(at 0 0 270)
			(layer "F.SilkS")
			(hide yes)
			(effects
				(font
					(size 1.27 1.27)
				)
			)
		)
		(property "Value" "240"
			(at -0.148158 1.3462 0)
			(unlocked yes)
			(layer "F.Fab")
			(hide yes)
			(effects
				(font
					(size 1.27 0.9652)
					(thickness 0.000001)
				)
				(justify left)
			)
		)
		(property "Device Type" "REST0009"
			(at -0.148158 1.3462 0)
			(unlocked yes)
			(layer "F.Fab")
			(hide yes)
			(effects
				(font
					(size 1.27 0.9652)
					(thickness 0.000001)
				)
				(justify left)
			)
		)
		(duplicate_pad_numbers_are_jumpers no)
		(fp_poly
			(pts
				(xy 0.635 1.0668) (xy 0.635 -1.0668) (xy -0.635 -1.0668) (xy -0.635 1.0668)
			)
			(stroke
				(width 0)
				(type default)
			)
			(fill no)
			(layer "F.CrtYd")
		)
		(fp_line
			(start -0.254 0.508)
			(end -0.254 -0.508)
			(stroke
				(width 0.0254)
				(type default)
			)
			(layer "F.Fab")
		)
		(fp_line
			(start 0.254 0.508)
			(end -0.254 0.508)
			(stroke
				(width 0.0254)
				(type default)
			)
			(layer "F.Fab")
		)
		(fp_line
			(start -0.254 -0.508)
			(end 0.254 -0.508)
			(stroke
				(width 0.0254)
				(type default)
			)
			(layer "F.Fab")
		)
		(fp_line
			(start 0.254 -0.508)
			(end 0.254 0.508)
			(stroke
				(width 0.0254)
				(type default)
			)
			(layer "F.Fab")
		)
		(pad "1" smd rect
			(at 0 -0.4191 270)
			(size 0.508 0.5334)
			(layers "F.Cu" "F.Mask" "F.Paste")
			(net "0.7V_REF")
		)
		(pad "2" smd rect
			(at 0 0.4191 270)
			(size 0.508 0.5334)
			(layers "F.Cu" "F.Mask" "F.Paste")
			(net "EXT_3.3V")
		)
		(zone
			(layer "F.Cu")
			(hatch none 0.5)
			(connect_pads
				(clearance 0)
			)
			(min_thickness 0.25)
			(keepout
				(tracks not_allowed)
				(vias allowed)
				(pads allowed)
				(copperpour not_allowed)
				(footprints allowed)
			)
			(placement
				(enabled no)
				(sheetname "")
			)
			(fill
				(thermal_gap 0.5)
				(thermal_bridge_width 0.5)
				(island_removal_mode 0)
			)
			(polygon
				(pts
					(xy 45.4914 53.1622) (xy 45.4406 53.1622) (xy 45.4406 53.1114) (xy 45.4914 53.1114)
				)
			)
		)
	)
	(footprint ""
		(layer "F.Cu")
		(at 28.321 32.639 180)
		(property "Reference" "R92"
			(at 0 0 180)
			(layer "F.SilkS")
			(hide yes)
			(effects
				(font
					(size 1.27 1.27)
				)
			)
		)
		(property "Value" "4.75K"
			(at -0.148158 1.3462 270)
			(unlocked yes)
			(layer "F.Fab")
			(hide yes)
			(effects
				(font
					(size 1.27 0.9652)
					(thickness 0.000001)
				)
				(justify left)
			)
		)
		(property "Device Type" "REST4024"
			(at -0.148158 1.3462 270)
			(unlocked yes)
			(layer "F.Fab")
			(hide yes)
			(effects
				(font
					(size 1.27 0.9652)
					(thickness 0.000001)
				)
				(justify left)
			)
		)
		(duplicate_pad_numbers_are_jumpers no)
		(fp_poly
			(pts
				(xy 0.635 1.0668) (xy 0.635 -1.0668) (xy -0.635 -1.0668) (xy -0.635 1.0668)
			)
			(stroke
				(width 0)
				(type default)
			)
			(fill no)
			(layer "F.CrtYd")
		)
		(fp_line
			(start 0.254 0.508)
			(end -0.254 0.508)
			(stroke
				(width 0.0254)
				(type default)
			)
			(layer "F.Fab")
		)
		(fp_line
			(start 0.254 -0.508)
			(end 0.254 0.508)
			(stroke
				(width 0.0254)
				(type default)
			)
			(layer "F.Fab")
		)
		(fp_line
			(start -0.254 0.508)
			(end -0.254 -0.508)
			(stroke
				(width 0.0254)
				(type default)
			)
			(layer "F.Fab")
		)
		(fp_line
			(start -0.254 -0.508)
			(end 0.254 -0.508)
			(stroke
				(width 0.0254)
				(type default)
			)
			(layer "F.Fab")
		)
		(pad "1" smd rect
			(at 0 -0.4191 180)
			(size 0.508 0.5334)
			(layers "F.Cu" "F.Mask" "F.Paste")
			(net "_NFP_CORE_VID1")
		)
		(pad "2" smd rect
			(at 0 0.4191 180)
			(size 0.508 0.5334)
			(layers "F.Cu" "F.Mask" "F.Paste")
			(net "VDD_1.2V")
		)
		(zone
			(layer "F.Cu")
			(hatch none 0.5)
			(connect_pads
				(clearance 0)
			)
			(min_thickness 0.25)
			(keepout
				(tracks not_allowed)
				(vias allowed)
				(pads allowed)
				(copperpour not_allowed)
				(footprints allowed)
			)
			(placement
				(enabled no)
				(sheetname "")
			)
			(fill
				(thermal_gap 0.5)
				(thermal_bridge_width 0.5)
				(island_removal_mode 0)
			)
			(polygon
				(pts
					(xy 28.2956 32.6644) (xy 28.2956 32.6136) (xy 28.3464 32.6136) (xy 28.3464 32.6644)
				)
			)
		)
	)
	(footprint ""
		(layer "F.Cu")
		(at 19.558 2.9972 180)
		(property "Reference" "C284"
			(at 0 0 180)
			(layer "F.SilkS")
			(hide yes)
			(effects
				(font
					(size 1.27 1.27)
				)
			)
		)
		(property "Value" "0.1UF"
			(at -0.091846 0.2921 270)
			(unlocked yes)
			(layer "F.Fab")
			(hide yes)
			(effects
				(font
					(size 0.7874 0.5842)
					(thickness 0.2032)
				)
				(justify left)
			)
		)
		(property "Device Type" "CAPC0073"
			(at -0.091846 0.2921 270)
			(unlocked yes)
			(layer "F.Fab")
			(hide yes)
			(effects
				(font
					(size 0.7874 0.5842)
					(thickness 0.2032)
				)
				(justify left)
			)
		)
		(duplicate_pad_numbers_are_jumpers no)
		(fp_poly
			(pts
				(xy 0.635 1.0668) (xy 0.635 -1.0668) (xy -0.635 -1.0668) (xy -0.635 1.0668)
			)
			(stroke
				(width 0)
				(type default)
			)
			(fill no)
			(layer "F.CrtYd")
		)
		(fp_line
			(start 0.254 0.508)
			(end -0.254 0.508)
			(stroke
				(width 0.0254)
				(type default)
			)
			(layer "F.Fab")
		)
		(fp_line
			(start 0.254 -0.508)
			(end 0.254 0.508)
			(stroke
				(width 0.0254)
				(type default)
			)
			(layer "F.Fab")
		)
		(fp_line
			(start -0.254 0.508)
			(end -0.254 -0.508)
			(stroke
				(width 0.0254)
				(type default)
			)
			(layer "F.Fab")
		)
		(fp_line
			(start -0.254 -0.508)
			(end 0.254 -0.508)
			(stroke
				(width 0.0254)
				(type default)
			)
			(layer "F.Fab")
		)
		(pad "1" smd rect
			(at 0 -0.4191 180)
			(size 0.508 0.5334)
			(layers "F.Cu" "F.Mask" "F.Paste")
			(net "EXT_3.3V")
		)
		(pad "2" smd rect
			(at 0 0.4191 180)
			(size 0.508 0.5334)
			(layers "F.Cu" "F.Mask" "F.Paste")
			(net "GND")
		)
		(zone
			(layer "F.Cu")
			(hatch none 0.5)
			(connect_pads
				(clearance 0)
			)
			(min_thickness 0.25)
			(keepout
				(tracks not_allowed)
				(vias allowed)
				(pads allowed)
				(copperpour not_allowed)
				(footprints allowed)
			)
			(placement
				(enabled no)
				(sheetname "")
			)
			(fill
				(thermal_gap 0.5)
				(thermal_bridge_width 0.5)
				(island_removal_mode 0)
			)
			(polygon
				(pts
					(xy 19.5326 3.0226) (xy 19.5326 2.9718) (xy 19.5834 2.9718) (xy 19.5834 3.0226)
				)
			)
		)
	)
	(footprint ""
		(layer "F.Cu")
		(at 79.450997 14.256004)
		(property "Reference" "V2_A-CAS"
			(at 0 0 0)
			(layer "F.SilkS")
			(hide yes)
			(effects
				(font
					(size 1.27 1.27)
				)
			)
		)
		(property "Value" ""
			(at 0 0 0)
			(layer "F.Fab")
			(effects
				(font
					(size 1.27 1.27)
				)
			)
		)
		(duplicate_pad_numbers_are_jumpers no)
		(pad "1" thru_hole circle
			(at 0 0)
			(size 0.762 0.762)
			(drill 0.20574)
			(layers "*.Cu" "*.Mask")
			(remove_unused_layers no)
			(net "DDR0_32A_CAS_L")
			(clearance 0.127)
			(thermal_gap 0.127)
			(padstack
				(mode front_inner_back)
				(layer "Inner"
					(shape circle)
					(size 0.4572 0.4572)
					(clearance 0.1143)
				)
				(layer "B.Cu"
					(shape circle)
					(size 0.4572 0.4572)
					(clearance 0.1143)
				)
			)
		)
	)
	(footprint ""
		(layer "F.Cu")
		(at 83.693 26.924)
		(property "Reference" "R215"
			(at 0 0 0)
			(layer "F.SilkS")
			(hide yes)
			(effects
				(font
					(size 1.27 1.27)
				)
			)
		)
		(property "Value" "39.0"
			(at -0.148158 1.3462 90)
			(unlocked yes)
			(layer "F.Fab")
			(hide yes)
			(effects
				(font
					(size 1.27 0.9652)
					(thickness 0.000001)
				)
				(justify left)
			)
		)
		(property "Device Type" "REST0108"
			(at -0.148158 1.3462 90)
			(unlocked yes)
			(layer "F.Fab")
			(hide yes)
			(effects
				(font
					(size 1.27 0.9652)
					(thickness 0.000001)
				)
				(justify left)
			)
		)
		(duplicate_pad_numbers_are_jumpers no)
		(fp_poly
			(pts
				(xy 0.635 1.0668) (xy 0.635 -1.0668) (xy -0.635 -1.0668) (xy -0.635 1.0668)
			)
			(stroke
				(width 0)
				(type default)
			)
			(fill no)
			(layer "F.CrtYd")
		)
		(fp_line
			(start -0.254 -0.508)
			(end 0.254 -0.508)
			(stroke
				(width 0.0254)
				(type default)
			)
			(layer "F.Fab")
		)
		(fp_line
			(start -0.254 0.508)
			(end -0.254 -0.508)
			(stroke
				(width 0.0254)
				(type default)
			)
			(layer "F.Fab")
		)
		(fp_line
			(start 0.254 -0.508)
			(end 0.254 0.508)
			(stroke
				(width 0.0254)
				(type default)
			)
			(layer "F.Fab")
		)
		(fp_line
			(start 0.254 0.508)
			(end -0.254 0.508)
			(stroke
				(width 0.0254)
				(type default)
			)
			(layer "F.Fab")
		)
		(pad "1" smd rect
			(at 0 -0.4191)
			(size 0.508 0.5334)
			(layers "F.Cu" "F.Mask" "F.Paste")
			(net "DDR0_32A_A9")
		)
		(pad "2" smd rect
			(at 0 0.4191)
			(size 0.508 0.5334)
			(layers "F.Cu" "F.Mask" "F.Paste")
			(net "DDR_VTT")
		)
		(zone
			(layer "F.Cu")
			(hatch none 0.5)
			(connect_pads
				(clearance 0)
			)
			(min_thickness 0.25)
			(keepout
				(tracks not_allowed)
				(vias allowed)
				(pads allowed)
				(copperpour not_allowed)
				(footprints allowed)
			)
			(placement
				(enabled no)
				(sheetname "")
			)
			(fill
				(thermal_gap 0.5)
				(thermal_bridge_width 0.5)
				(island_removal_mode 0)
			)
			(polygon
				(pts
					(xy 83.7184 26.8986) (xy 83.7184 26.9494) (xy 83.6676 26.9494) (xy 83.6676 26.8986)
				)
			)
		)
	)
	(footprint ""
		(layer "F.Cu")
		(at 34.29 2.286)
		(property "Reference" "R14"
			(at -1.24333 -0.889 90)
			(unlocked yes)
			(layer "F.SilkS")
			(effects
				(font
					(size 0.7874 0.5842)
					(thickness 0.127)
				)
				(justify left)
			)
		)
		(property "Value" "4.75K"
			(at -0.148158 1.3462 90)
			(unlocked yes)
			(layer "F.Fab")
			(hide yes)
			(effects
				(font
					(size 1.27 0.9652)
					(thickness 0.000001)
				)
				(justify left)
			)
		)
		(property "Device Type" "REST4024"
			(at -0.148158 1.3462 90)
			(unlocked yes)
			(layer "F.Fab")
			(hide yes)
			(effects
				(font
					(size 1.27 0.9652)
					(thickness 0.000001)
				)
				(justify left)
			)
		)
		(duplicate_pad_numbers_are_jumpers no)
		(fp_poly
			(pts
				(xy 0.635 1.0668) (xy 0.635 -1.0668) (xy -0.635 -1.0668) (xy -0.635 1.0668)
			)
			(stroke
				(width 0)
				(type default)
			)
			(fill no)
			(layer "F.CrtYd")
		)
		(fp_line
			(start -0.254 -0.508)
			(end 0.254 -0.508)
			(stroke
				(width 0.0254)
				(type default)
			)
			(layer "F.Fab")
		)
		(fp_line
			(start -0.254 0.508)
			(end -0.254 -0.508)
			(stroke
				(width 0.0254)
				(type default)
			)
			(layer "F.Fab")
		)
		(fp_line
			(start 0.254 -0.508)
			(end 0.254 0.508)
			(stroke
				(width 0.0254)
				(type default)
			)
			(layer "F.Fab")
		)
		(fp_line
			(start 0.254 0.508)
			(end -0.254 0.508)
			(stroke
				(width 0.0254)
				(type default)
			)
			(layer "F.Fab")
		)
		(pad "1" smd rect
			(at 0 -0.4191)
			(size 0.508 0.5334)
			(layers "F.Cu" "F.Mask" "F.Paste")
			(net "EXT_3.3V")
		)
		(pad "2" smd rect
			(at 0 0.4191)
			(size 0.508 0.5334)
			(layers "F.Cu" "F.Mask" "F.Paste")
			(net "3N2287")
		)
		(zone
			(layer "F.Cu")
			(hatch none 0.5)
			(connect_pads
				(clearance 0)
			)
			(min_thickness 0.25)
			(keepout
				(tracks not_allowed)
				(vias allowed)
				(pads allowed)
				(copperpour not_allowed)
				(footprints allowed)
			)
			(placement
				(enabled no)
				(sheetname "")
			)
			(fill
				(thermal_gap 0.5)
				(thermal_bridge_width 0.5)
				(island_removal_mode 0)
			)
			(polygon
				(pts
					(xy 34.3154 2.2606) (xy 34.3154 2.3114) (xy 34.2646 2.3114) (xy 34.2646 2.2606)
				)
			)
		)
	)
	(footprint ""
		(layer "F.Cu")
		(at 81.4578 32.258 -90)
		(property "Reference" "C218"
			(at -0.86233 1.8288 0)
			(unlocked yes)
			(layer "F.SilkS")
			(effects
				(font
					(size 0.7874 0.5842)
					(thickness 0.127)
				)
				(justify left)
			)
		)
		(property "Value" "1UF"
			(at -0.091846 0.2921 0)
			(unlocked yes)
			(layer "F.Fab")
			(hide yes)
			(effects
				(font
					(size 0.7874 0.5842)
					(thickness 0.2032)
				)
				(justify left)
			)
		)
		(property "Device Type" "CAPC0028"
			(at -0.091846 0.2921 0)
			(unlocked yes)
			(layer "F.Fab")
			(hide yes)
			(effects
				(font
					(size 0.7874 0.5842)
					(thickness 0.2032)
				)
				(justify left)
			)
		)
		(duplicate_pad_numbers_are_jumpers no)
		(fp_poly
			(pts
				(xy 0.635 1.0668) (xy 0.635 -1.0668) (xy -0.635 -1.0668) (xy -0.635 1.0668)
			)
			(stroke
				(width 0)
				(type default)
			)
			(fill no)
			(layer "F.CrtYd")
		)
		(fp_line
			(start -0.254 0.508)
			(end -0.254 -0.508)
			(stroke
				(width 0.0254)
				(type default)
			)
			(layer "F.Fab")
		)
		(fp_line
			(start 0.254 0.508)
			(end -0.254 0.508)
			(stroke
				(width 0.0254)
				(type default)
			)
			(layer "F.Fab")
		)
		(fp_line
			(start -0.254 -0.508)
			(end 0.254 -0.508)
			(stroke
				(width 0.0254)
				(type default)
			)
			(layer "F.Fab")
		)
		(fp_line
			(start 0.254 -0.508)
			(end 0.254 0.508)
			(stroke
				(width 0.0254)
				(type default)
			)
			(layer "F.Fab")
		)
		(pad "1" smd rect
			(at 0 -0.4191 270)
			(size 0.508 0.5334)
			(layers "F.Cu" "F.Mask" "F.Paste")
			(net "DDR_VDDQ")
		)
		(pad "2" smd rect
			(at 0 0.4191 270)
			(size 0.508 0.5334)
			(layers "F.Cu" "F.Mask" "F.Paste")
			(net "GND")
		)
		(zone
			(layer "F.Cu")
			(hatch none 0.5)
			(connect_pads
				(clearance 0)
			)
			(min_thickness 0.25)
			(keepout
				(tracks not_allowed)
				(vias allowed)
				(pads allowed)
				(copperpour not_allowed)
				(footprints allowed)
			)
			(placement
				(enabled no)
				(sheetname "")
			)
			(fill
				(thermal_gap 0.5)
				(thermal_bridge_width 0.5)
				(island_removal_mode 0)
			)
			(polygon
				(pts
					(xy 81.4832 32.2834) (xy 81.4324 32.2834) (xy 81.4324 32.2326) (xy 81.4832 32.2326)
				)
			)
		)
	)
	(footprint ""
		(layer "F.Cu")
		(at 32.766 32.639)
		(property "Reference" "R91"
			(at 0 0 0)
			(layer "F.SilkS")
			(hide yes)
			(effects
				(font
					(size 1.27 1.27)
				)
			)
		)
		(property "Value" "4.75K"
			(at -0.148158 1.3462 90)
			(unlocked yes)
			(layer "F.Fab")
			(hide yes)
			(effects
				(font
					(size 1.27 0.9652)
					(thickness 0.000001)
				)
				(justify left)
			)
		)
		(property "Device Type" "REST4024"
			(at -0.148158 1.3462 90)
			(unlocked yes)
			(layer "F.Fab")
			(hide yes)
			(effects
				(font
					(size 1.27 0.9652)
					(thickness 0.000001)
				)
				(justify left)
			)
		)
		(duplicate_pad_numbers_are_jumpers no)
		(fp_poly
			(pts
				(xy 0.635 1.0668) (xy 0.635 -1.0668) (xy -0.635 -1.0668) (xy -0.635 1.0668)
			)
			(stroke
				(width 0)
				(type default)
			)
			(fill no)
			(layer "F.CrtYd")
		)
		(fp_line
			(start -0.254 -0.508)
			(end 0.254 -0.508)
			(stroke
				(width 0.0254)
				(type default)
			)
			(layer "F.Fab")
		)
		(fp_line
			(start -0.254 0.508)
			(end -0.254 -0.508)
			(stroke
				(width 0.0254)
				(type default)
			)
			(layer "F.Fab")
		)
		(fp_line
			(start 0.254 -0.508)
			(end 0.254 0.508)
			(stroke
				(width 0.0254)
				(type default)
			)
			(layer "F.Fab")
		)
		(fp_line
			(start 0.254 0.508)
			(end -0.254 0.508)
			(stroke
				(width 0.0254)
				(type default)
			)
			(layer "F.Fab")
		)
		(pad "1" smd rect
			(at 0 -0.4191)
			(size 0.508 0.5334)
			(layers "F.Cu" "F.Mask" "F.Paste")
			(net "GND")
		)
		(pad "2" smd rect
			(at 0 0.4191)
			(size 0.508 0.5334)
			(layers "F.Cu" "F.Mask" "F.Paste")
			(net "_NFP_CORE_VID4")
		)
		(zone
			(layer "F.Cu")
			(hatch none 0.5)
			(connect_pads
				(clearance 0)
			)
			(min_thickness 0.25)
			(keepout
				(tracks not_allowed)
				(vias allowed)
				(pads allowed)
				(copperpour not_allowed)
				(footprints allowed)
			)
			(placement
				(enabled no)
				(sheetname "")
			)
			(fill
				(thermal_gap 0.5)
				(thermal_bridge_width 0.5)
				(island_removal_mode 0)
			)
			(polygon
				(pts
					(xy 32.7914 32.6136) (xy 32.7914 32.6644) (xy 32.7406 32.6644) (xy 32.7406 32.6136)
				)
			)
		)
	)
	(footprint ""
		(layer "F.Cu")
		(at 18.415 6.604 180)
		(property "Reference" "R391"
			(at 0 0 180)
			(layer "F.SilkS")
			(hide yes)
			(effects
				(font
					(size 1.27 1.27)
				)
			)
		)
		(property "Value" "0"
			(at -0.148158 1.3462 270)
			(unlocked yes)
			(layer "F.Fab")
			(hide yes)
			(effects
				(font
					(size 1.27 0.9652)
					(thickness 0.000001)
				)
				(justify left)
			)
		)
		(property "Device Type" "REST1111"
			(at -0.148158 1.3462 270)
			(unlocked yes)
			(layer "F.Fab")
			(hide yes)
			(effects
				(font
					(size 1.27 0.9652)
					(thickness 0.000001)
				)
				(justify left)
			)
		)
		(duplicate_pad_numbers_are_jumpers no)
		(fp_poly
			(pts
				(xy 0.635 1.0668) (xy 0.635 -1.0668) (xy -0.635 -1.0668) (xy -0.635 1.0668)
			)
			(stroke
				(width 0)
				(type default)
			)
			(fill no)
			(layer "F.CrtYd")
		)
		(fp_line
			(start 0.254 0.508)
			(end -0.254 0.508)
			(stroke
				(width 0.0254)
				(type default)
			)
			(layer "F.Fab")
		)
		(fp_line
			(start 0.254 -0.508)
			(end 0.254 0.508)
			(stroke
				(width 0.0254)
				(type default)
			)
			(layer "F.Fab")
		)
		(fp_line
			(start -0.254 0.508)
			(end -0.254 -0.508)
			(stroke
				(width 0.0254)
				(type default)
			)
			(layer "F.Fab")
		)
		(fp_line
			(start -0.254 -0.508)
			(end 0.254 -0.508)
			(stroke
				(width 0.0254)
				(type default)
			)
			(layer "F.Fab")
		)
		(pad "1" smd rect
			(at 0 -0.4191 180)
			(size 0.508 0.5334)
			(layers "F.Cu" "F.Mask" "F.Paste")
			(net "NFP_SMBUS_ALERT_L")
		)
		(pad "2" smd rect
			(at 0 0.4191 180)
			(size 0.508 0.5334)
			(layers "F.Cu" "F.Mask" "F.Paste")
			(net "SMBUS_ALERT_L")
		)
		(zone
			(layer "F.Cu")
			(hatch none 0.5)
			(connect_pads
				(clearance 0)
			)
			(min_thickness 0.25)
			(keepout
				(tracks not_allowed)
				(vias allowed)
				(pads allowed)
				(copperpour not_allowed)
				(footprints allowed)
			)
			(placement
				(enabled no)
				(sheetname "")
			)
			(fill
				(thermal_gap 0.5)
				(thermal_bridge_width 0.5)
				(island_removal_mode 0)
			)
			(polygon
				(pts
					(xy 18.3896 6.6294) (xy 18.3896 6.5786) (xy 18.4404 6.5786) (xy 18.4404 6.6294)
				)
			)
		)
	)
)
